# S9S_MB_2U (Grand Teton) — schematic netlist excerpt (pin names and nets, part order shuffled) for the footprints in the layout excerpt that follows; sources: Cadence DE-HDL packaged netlist, KiCad conversion of 03242023_DA0F0TMBIJ0_F0T_Motherboard_J_brd_V01_OCP.brd

R4548  Q_RES  100K 1% CHIP  pkg 0402LF  page 145 : A = SWB_HSC_EN ; B = GND
R2670  Q_RES  4.7K 5% EMPTY  pkg 0402LF  page 234 : A = P3V3_AUX ; B = I3C_BMC_SWB_BUF_R_SCL

(kicad_pcb
	(version 20260206)
	(generator "pcbnew")
	(generator_version "10.0")
	(general
		(thickness 1.6)
		(legacy_teardrops no)
	)
	(paper "A4")
	(title_block
		(title "03242023_DA0F0TMBIJ0_F0T_Motherboard_J_brd_V01_OCP.brd")
		(comment 1 "Grand Teton / footprints 1220-1221 of 6105")
	)
	(layers
		(0 "F.Cu" signal "TOP")
		(4 "In1.Cu" signal "GND")
		(6 "In2.Cu" signal "IN1")
		(8 "In3.Cu" signal "GND1")
		(10 "In4.Cu" signal "IN2")
		(12 "In5.Cu" signal "GND2")
		(14 "In6.Cu" signal "IN3")
		(16 "In7.Cu" signal "GND3")
		(18 "In8.Cu" signal "VCC")
		(20 "In9.Cu" signal "VCC1")
		(22 "In10.Cu" signal "GND4")
		(24 "In11.Cu" signal "IN4")
		(26 "In12.Cu" signal "GND5")
		(28 "In13.Cu" signal "IN5")
		(30 "In14.Cu" signal "GND6")
		(32 "In15.Cu" signal "IN6")
		(34 "In16.Cu" signal "GND7")
		(2 "B.Cu" signal "BOTTOM")
		(9 "F.Adhes" user "F.Adhesive")
		(11 "B.Adhes" user "B.Adhesive")
		(13 "F.Paste" user "Package Geometry/Pastemask Top")
		(15 "B.Paste" user "Package Geometry/Pastemask Bottom")
		(5 "F.SilkS" user "Ref Des/Silkscreen Top")
		(7 "B.SilkS" user "Ref Des/Silkscreen Bottom")
		(1 "F.Mask" user "Board Geometry/Soldermask Top")
		(3 "B.Mask" user "Board Geometry/Soldermask Bottom")
		(17 "Dwgs.User" user "User.Drawings")
		(19 "Cmts.User" user "User.Comments")
		(21 "Eco1.User" user "User.Eco1")
		(23 "Eco2.User" user "User.Eco2")
		(25 "Edge.Cuts" user "Board Geometry/Outline")
		(27 "Margin" user)
		(31 "F.CrtYd" user "Package Geometry/Place Bound Top")
		(29 "B.CrtYd" user "Package Geometry/Place Bound Bottom")
		(35 "F.Fab" user "Ref Des/Assembly Top")
		(33 "B.Fab" user "Ref Des/Assembly Bottom")
	)
	(footprint ""
		(layer "F.Cu")
		(at 355.2698 -406.852628 -90)
		(property "Reference" "R4548"
			(at 0 0 270)
			(layer "F.SilkS")
			(hide yes)
			(effects
				(font
					(size 1.27 1.27)
				)
			)
		)
		(property "Value" ""
			(at 0 0 270)
			(layer "F.Fab")
			(effects
				(font
					(size 1.27 1.27)
				)
			)
		)
		(duplicate_pad_numbers_are_jumpers no)
		(fp_line
			(start -0.7874 0.4064)
			(end -0.7874 -0.4064)
			(stroke
				(width 0.1524)
				(type default)
			)
			(layer "F.SilkS")
		)
		(fp_line
			(start 0.7874 0.4064)
			(end -0.7874 0.4064)
			(stroke
				(width 0.1524)
				(type default)
			)
			(layer "F.SilkS")
		)
		(fp_line
			(start -0.7874 -0.4064)
			(end 0.7874 -0.4064)
			(stroke
				(width 0.1524)
				(type default)
			)
			(layer "F.SilkS")
		)
		(fp_line
			(start 0.7874 -0.4064)
			(end 0.7874 0.4064)
			(stroke
				(width 0.1524)
				(type default)
			)
			(layer "F.SilkS")
		)
		(fp_line
			(start -0.67945 0.3048)
			(end -0.67945 -0.305054)
			(stroke
				(width 0.1)
				(type default)
			)
			(layer "F.Fab")
		)
		(fp_line
			(start -0.12065 0.3048)
			(end -0.67945 0.3048)
			(stroke
				(width 0.1)
				(type default)
			)
			(layer "F.Fab")
		)
		(fp_line
			(start 0.120396 0.3048)
			(end 0.120396 0.2794)
			(stroke
				(width 0.1)
				(type default)
			)
			(layer "F.Fab")
		)
		(fp_line
			(start 0.67945 0.3048)
			(end 0.120396 0.3048)
			(stroke
				(width 0.1)
				(type default)
			)
			(layer "F.Fab")
		)
		(fp_line
			(start -0.12065 0.2794)
			(end -0.12065 0.3048)
			(stroke
				(width 0.1)
				(type default)
			)
			(layer "F.Fab")
		)
		(fp_line
			(start 0.120396 0.2794)
			(end -0.12065 0.2794)
			(stroke
				(width 0.1)
				(type default)
			)
			(layer "F.Fab")
		)
		(fp_line
			(start -0.12065 -0.2794)
			(end 0.12065 -0.2794)
			(stroke
				(width 0.1)
				(type default)
			)
			(layer "F.Fab")
		)
		(fp_line
			(start 0.12065 -0.2794)
			(end 0.12065 -0.3048)
			(stroke
				(width 0.1)
				(type default)
			)
			(layer "F.Fab")
		)
		(fp_line
			(start 0.12065 -0.3048)
			(end 0.67945 -0.3048)
			(stroke
				(width 0.1)
				(type default)
			)
			(layer "F.Fab")
		)
		(fp_line
			(start 0.67945 -0.3048)
			(end 0.67945 0.3048)
			(stroke
				(width 0.1)
				(type default)
			)
			(layer "F.Fab")
		)
		(fp_line
			(start -0.67945 -0.305054)
			(end -0.12065 -0.305054)
			(stroke
				(width 0.1)
				(type default)
			)
			(layer "F.Fab")
		)
		(fp_line
			(start -0.12065 -0.305054)
			(end -0.12065 -0.2794)
			(stroke
				(width 0.1)
				(type default)
			)
			(layer "F.Fab")
		)
		(pad "1" smd circle
			(at -0.40005 0 270)
			(size 0 0)
			(layers "F.Cu" "F.Mask" "F.Paste")
			(net "SWB_HSC_EN")
		)
		(pad "2" smd circle
			(at 0.40005 0 270)
			(size 0 0)
			(layers "F.Cu" "F.Mask" "F.Paste")
			(net "GND")
		)
	)
	(footprint ""
		(layer "F.Cu")
		(at 357.735632 -398.789398)
		(property "Reference" "R2670"
			(at 0 0 0)
			(layer "F.SilkS")
			(hide yes)
			(effects
				(font
					(size 1.27 1.27)
				)
			)
		)
		(property "Value" ""
			(at 0 0 0)
			(layer "F.Fab")
			(effects
				(font
					(size 1.27 1.27)
				)
			)
		)
		(duplicate_pad_numbers_are_jumpers no)
		(fp_line
			(start -0.7874 -0.4064)
			(end 0.7874 -0.4064)
			(stroke
				(width 0.1524)
				(type default)
			)
			(layer "F.SilkS")
		)
		(fp_line
			(start -0.7874 0.4064)
			(end -0.7874 -0.4064)
			(stroke
				(width 0.1524)
				(type default)
			)
			(layer "F.SilkS")
		)
		(fp_line
			(start 0.7874 -0.4064)
			(end 0.7874 0.4064)
			(stroke
				(width 0.1524)
				(type default)
			)
			(layer "F.SilkS")
		)
		(fp_line
			(start 0.7874 0.4064)
			(end -0.7874 0.4064)
			(stroke
				(width 0.1524)
				(type default)
			)
			(layer "F.SilkS")
		)
		(fp_line
			(start -0.67945 -0.305054)
			(end -0.12065 -0.305054)
			(stroke
				(width 0.1)
				(type default)
			)
			(layer "F.Fab")
		)
		(fp_line
			(start -0.67945 0.3048)
			(end -0.67945 -0.305054)
			(stroke
				(width 0.1)
				(type default)
			)
			(layer "F.Fab")
		)
		(fp_line
			(start -0.12065 -0.305054)
			(end -0.12065 -0.2794)
			(stroke
				(width 0.1)
				(type default)
			)
			(layer "F.Fab")
		)
		(fp_line
			(start -0.12065 -0.2794)
			(end 0.12065 -0.2794)
			(stroke
				(width 0.1)
				(type default)
			)
			(layer "F.Fab")
		)
		(fp_line
			(start -0.12065 0.2794)
			(end -0.12065 0.3048)
			(stroke
				(width 0.1)
				(type default)
			)
			(layer "F.Fab")
		)
		(fp_line
			(start -0.12065 0.3048)
			(end -0.67945 0.3048)
			(stroke
				(width 0.1)
				(type default)
			)
			(layer "F.Fab")
		)
		(fp_line
			(start 0.120396 0.2794)
			(end -0.12065 0.2794)
			(stroke
				(width 0.1)
				(type default)
			)
			(layer "F.Fab")
		)
		(fp_line
			(start 0.120396 0.3048)
			(end 0.120396 0.2794)
			(stroke
				(width 0.1)
				(type default)
			)
			(layer "F.Fab")
		)
		(fp_line
			(start 0.12065 -0.3048)
			(end 0.67945 -0.3048)
			(stroke
				(width 0.1)
				(type default)
			)
			(layer "F.Fab")
		)
		(fp_line
			(start 0.12065 -0.2794)
			(end 0.12065 -0.3048)
			(stroke
				(width 0.1)
				(type default)
			)
			(layer "F.Fab")
		)
		(fp_line
			(start 0.67945 -0.3048)
			(end 0.67945 0.3048)
			(stroke
				(width 0.1)
				(type default)
			)
			(layer "F.Fab")
		)
		(fp_line
			(start 0.67945 0.3048)
			(end 0.120396 0.3048)
			(stroke
				(width 0.1)
				(type default)
			)
			(layer "F.Fab")
		)
		(pad "1" smd circle
			(at -0.40005 0)
			(size 0 0)
			(layers "F.Cu" "F.Mask" "F.Paste")
			(net "P3V3_AUX")
		)
		(pad "2" smd circle
			(at 0.40005 0)
			(size 0 0)
			(layers "F.Cu" "F.Mask" "F.Paste")
			(net "I3C_BMC_SWB_BUF_R_SCL")
		)
	)
)
